CONCISE PART LIST - 1  
10M02SCU169C8G-10M02SCU169C8G,A AJ10M020T00              1       
74HC1G126GW-74HC1G126GW,SMLF,IA AL1G0126007              4       
74LVC1G07GW-74LVC1G07GW,SMLF,IA ALVC1G07002              1       
74LVC1G17GW-74LVC1G17GW,SMLF,IA AL1G0017K01              1       
AP22811AW57-AP22811AW5-7,SMLF,A AL022811000              1       
AST2600A1GP-AST2600A1-GP,SMLF,A AJ026000T04              1       
BAT54C-BAT54C,SMLF,IC,BCBAT54CA BCBAT54CZ04              1       
BCM54612EB1KMLG-BCM54612EB1KMLA AL054612B00              1       
BZA462A-BZA462A,SMLF,IC,BCZA46A BCZA462AZ01              2       
CONN3_210P9103GBR1-CONN3_210-PA DFHD03MS212              1       
CONN7_4400547-CONN7_440054-7,TA DFHD07MS405              1       
CONN9_GSB311131HR-CONN9_GSB311A DFHS09FR401              1       
DELTA_L-DELTA-L,THLF,EMPTY,TP24 TP24                     16      
DUMMY_SYMBOL-BMC_FLASH,MECH,MEA DUMMY8                   2       
DUMMY_SYMBOL-PB-E1_SMALL,MECH,A DUMMY3                   1       
DUMMY_SYMBOL-PCBA_LABEL_15X5,MA DUMMY4                   1       
DUMMY_SYMBOL-QUANTA_LOGO_7X26,A DUMMY1                   1       
DUMMY_SYMBOL-WEEE,MECH,EMPTY,DA DUMMY2                   1       
FCONN168_ME1016810106011-FCONNA GOLD195                  1       
FT234XDR-FT234XD-R,SMLF,IC,AL0A AL000234001              1       
HOLE_TH-EMPTY,DUMMY50 DUMMY50                  2       
HOLE_TH-EMPTY,HOLE620 HOLE620                  2       
HOLE_TH-EMPTY,HOLE1101 HOLE1101                 2       
HOLE_TH-EMPTY,HOLE1211 HOLE1211                 2       
IDTQS3VH257PAG_SMLF-IDTQS3VH25A AL000257K00              2       
K4A8G165WCBCTD-K4A8G165WC-BCTDA AKD5FGUT502              1       
M24128BWDW6TP-M24128-BWDW6TP,SA AKE30Z0K610              1       
MMBT39047F-MMBT3904-7-F,SMLF,IA BA0390400H0              2       
MOSFET_DUAL_6P-2N7002KDW,SMLF,A BAM70020047              1       
MOSFET_DUAL_6P-DMN2400UV-7,SMLA BAM24000000              1       
MOSFET_NCH_DUAL-2N7002KDW,SMLFA BAM70020047              1       
MOSFET_N_123-BSS123-7-F,SMLF,IA BAM01230014              1       
MOSFET_N_GSD-DMG6968U-7,SMLF,IA BAM69680000              2       
MOSFET_N_GSD-NX7002AK,SMLF,IC,A BAM70020062              1       
MOSFET_N_SMLF-BSS138K,BSS138K,A BAM138K0000              1       
MPQ8626GDZ-MPQ8626GD-Z,SMLF,ICA AL008626000              1       
MPQ8633AGLEC807Z-MPQ8633AGLE-CA AL008633007              1       
MTFC8GAKAJCN1MWT-MTFC8GAKAJCN-A AKE3QZPTL02              1       
MX66L1G45GMI08G-MX66L1G45GMI-0A AKE3LF-0Z00              1       
NB695GDZ-NB695GD-Z,SMLF,IC,AL0A AL000695001              2       
OSC4_7X25000018-25MHZ,SMLF,MISA BF625000023              2       
PCA9517ADP_SMLF-PCA9517ADP,IC,A AL009517K00              1       
PRTR5V0U2X-PRTR5V0U2X,SMLF,IC,A AL5V0U2X000              1       
Q_CAP_0402-0.1UF,10V,10%,EMPTYA CH4102K1B03              6       
Q_CAP_0402-0.1UF,10V,10%,X7R,TA CH4102K1B03              12      
Q_CAP_0402-0.1UF,25V,10%,EMPTYA CH4104K1B00              1       
Q_CAP_0402-0.1UF,25V,10%,X7R,CA CH4104K1B00              158     
Q_CAP_0402-0.22UF,16V,10%,EMPTA CH4223K1B00              1       
Q_CAP_0402-0.22UF,16V,10%,X7R,A CH4223K1B00              5       
Q_CAP_0402-100PF,50V,5%,EMPTY,A CH11006JB18              2       
Q_CAP_0402-100PF,50V,5%,NPO,CHA CH11006JB00              6       
Q_CAP_0402-10PF,50V,1%,NPO,TMPA CH0106F0B00              3       
Q_CAP_0402-10PF,50V,5%,COG,CH0A CH01006JB08              2       
Q_CAP_0402-1UF,16V,10%,EMPTY,TA CH5103K9B00              5       
Q_CAP_0402-2.2UF,10V,20%,X5R,TA CH5222M9B07              2       
Q_CAP_0402-2200PF,50V,10%,X7R,A CH22206KB16              1       
Q_CAP_0402-22PF,50V,5%,EMPTY,TA CH02206JB08              1       
Q_CAP_0402-3300PF,50V,10%,X7R,A CH2336K1B12              1       
Q_CAP_0402-4.7UF,10V,10%,X5R,CA CH5472K9B00              3       
Q_CAP_0402-470PF,50V,10%,X7R,TA CH14706KB18              5       
Q_CAP_0603-1UF,16V,10%,EMPTY,TA CH5103K1900              1       
Q_CAP_0805-22UF,4V,20%,X6S,TMPA CH622KMEA01              8       
Q_CAP_1206-47UF ,10V,20%,X5R,CA CH6472M9200              2       
Q_CAP_C0402-0.001UF,50V,10%,X7A CH30106KB19              6       
Q_CAP_C0402-0.01UF,50V,10%,EMPA CH31006KB18              3       
Q_CAP_C0402-0.01UF,50V,10%,X7RA CH31006KB18              12      
Q_CAP_C0402-0.1UF,16V,10%,EMPTA CH4103K1B08              1       
Q_CAP_C0402-0.1UF,16V,10%,X7R,A CH4103K1B08              4       
Q_CAP_C0402-0.1UF,25V,10%,X6S,A CH4104KEB00              1       
Q_CAP_C0402-10UF,10V,20%,X5R,CA CH6102M9B00              4       
Q_CAP_C0402-10UF,6.3V,20%,X6S,A CH6101MEB01              3       
Q_CAP_C0402-12PF,50V,5%,C0G,CHA CH01206JB05              2       
Q_CAP_C0402-1UF,25V,10%,EMPTY,A CH5104KEB02              1       
Q_CAP_C0402-1UF,25V,10%,X6S,CHA CH5104KEB02              53      
Q_CAP_C0402-1UF,6.3V,10%,EMPTYA CH5101KEB00              1       
Q_CAP_C0402-22UF,6.3V,20%,X5R,A CH6221M9B01              2       
Q_CAP_C0402-33PF,50V,1%,C0G,CHA CH0336F0B00              3       
Q_CAP_C0402-4.7UF,10V,10%,X5R,A CH5472K9B02              2       
Q_CAP_C0402-4700P,25V,10%,EMPTA CH2474K1B08              1       
Q_CAP_C0402-68PF,50V,5%,COG,CHA CH06806JB01              1       
Q_CAP_C0603-10UF,16V,20%,X6S,CA CH6103ME902              3       
Q_CAP_C0603-22UF,10V,20%,EMPTYA CH6222M9901              1       
Q_CAP_C0603-22UF,10V,20%,X5R,CA CH6222M9901              7       
Q_CAP_C0603-22UF,6.3V,20%,EMPTA CH6221ME900              1       
Q_CAP_C0603-22UF,6.3V,20%,X6S,A CH6221ME900              7       
Q_CAP_C0603-4.7UF,25V,10%,X6S,A CH5474KE906              1       
Q_CAP_C0805-10UF,25V,10%,X6S,CA CH6104KEA00              12      
Q_CAP_C0805-22UF,10V,20%,X6S,CA CH6222MEA00              4       
Q_CAP_C0805-22UF,16V,20%,X6S,CA CH6223MEA00              5       
Q_CAP_C0805-22UF,25V,20%,X5R,CA CH6224M9A00              2       
Q_DIODE_SMLF-SDMK0340L-7-F,IC,A BC000340033              1       
Q_FUSE_SMLF-0.5A/6V,IC,DK050TPA DK050TPU011              1       
Q_FUSE_SMLF-1.1A/8V,IC,DK110TPA DK110TPU003              1       
Q_INDUCTOR4P_12-67/320MA,320MAA CX21SN67000              1       
Q_INDUCTOR4P_12-67/320MA,320MAB CX21SN67000              1       
Q_INDUCTOR_SMLF-1UH,IND,CV-10BA CV-10B0MZ13              2       
Q_INDUCTOR_SMLF-220/1500MA,INDA CX221T15000              1       
Q_INDUCTOR_SMLF-3.3UH/6A,IND,CA CV-3360MZ07              1       
Q_INDUCTOR_SMLF-4.7UH,IND,CV-4A CV-47A0MZ10              1       
Q_INDUCTOR_SMLF-47/300MA,IND,CA CX8BA470003              3       
Q_INDUCTOR_SMLF-BLM15PX121SN1DA CX5PX121001              5       
Q_INDUCTOR_SMLF-BLM18EG121SN1DA CX8EG121000              3       
Q_INDUCTOR_SMLF-BLM18PG121SN1DA CX8PG121009              14      
Q_INDUCTOR_SMLF-BLM18PG121SN1DB CX8PG121009              1       
Q_INDUCTOR_SMLF-BLM18SN220TN1DA CX220TN1001              4       
Q_LED_SMLF-LED_BLUE,12-215/BHCA BEBL0261Z00              2       
Q_LED_SMLF-LED_GREEN,19-213/GVA BEGR0278Z00              5       
Q_LED_SMLF-LED_RED,19-217/R6C-A BERD0034Z07              4       
Q_RES_0201LF-1.5K,1%,1/20W,CHIA CS21501FE01              1       
Q_RES_0201LF-27.4,1%,1/20W,CHIA CS02741FE07              2       
Q_RES_0201LF-47K,1%,1/20W,CHIPA CS34701FE00              1       
Q_RES_0402LF -49.9K,1%,1/16W ,A CS34992FB10              2       
Q_RES_0402LF-0,5%,1/16W,CHIP,CA CS00002JB38              108     
Q_RES_0402LF-0,5%,1/16W,EMPTY,A CS00002JB38              27      
Q_RES_0402LF-1.24K,1%,1/16W,CHA CS21242FB20              1       
Q_RES_0402LF-1.5K,1%,1/16W,CHIA CS21502FB14              1       
Q_RES_0402LF-1.5K,1%,1/16W,EMPA CS21502FB14              1       
Q_RES_0402LF-1.69K,1%,1/16W,CHA CS21692FB01              1       
Q_RES_0402LF-10,1%,1/16W,CHIP,A CS01002FB21              1       
Q_RES_0402LF-100,1%,1/16W,CHIPA CS11002FB22              9       
Q_RES_0402LF-100,1%,1/16W,EMPTA CS11002FB22              3       
Q_RES_0402LF-100K,0.1%,1/16W,CA CS41002BB06              1       
Q_RES_0402LF-100K,1%,1/16W,CHIA CS41002FB28              11      
Q_RES_0402LF-100K,1%,1/16W,CHIB CS41002FB09              1       
Q_RES_0402LF-100K,1%,1/16W,EMPA CS41002FB09              1       
Q_RES_0402LF-100K,1%,1/16W,EMPB CS41002FB28              7       
Q_RES_0402LF-10K,0.10%,1/16W,CA CS31002BB00              14      
Q_RES_0402LF-10K,1%,1/16W,CHIPA CS31002FB26              24      
Q_RES_0402LF-10K,1%,1/16W,EMPTA CS31002FB26              12      
Q_RES_0402LF-10K,1%,1/16W,EMPTB CS31002FB13              1       
Q_RES_0402LF-12.4K,1%,1/16W,CHA CS31242FB13              2       
Q_RES_0402LF-120,1%,1/16W,CHIPA CS11202FB11              48      
Q_RES_0402LF-120,1%,1/16W,EMPTA CS11202FB11              2       
Q_RES_0402LF-12K,1%,1/16W,CHIPA CS31202FB15              2       
Q_RES_0402LF-13.3K,1%,1/16W,CHA CS21332FB02              1       
Q_RES_0402LF-15.8K,1%,1/16W,CHA CS31582FB12              1       
Q_RES_0402LF-150,1%,1/16W,CHIPA CS11502FB21              6       
Q_RES_0402LF-150K,1%,1/16W,CHIA CS41502FB18              1       
Q_RES_0402LF-15K,1%,1/16W,CHIPA CS31502FB24              1       
Q_RES_0402LF-1K,1%,1/16W,CHIP,A CS21002FB24              10      
Q_RES_0402LF-1K,1%,1/16W,EMPTYA CS21002FB24              5       
Q_RES_0402LF-1M,1%,1/16W,CHIP,A CS51002FB11              2       
Q_RES_0402LF-2.21K    ,1%  ,1/A CS22212FB11              2       
Q_RES_0402LF-2.2K ,5%,1/16W,CHA CS22202JB18              2       
Q_RES_0402LF-2.74K,1%,1/16W,CHA CS22742FB00              1       
Q_RES_0402LF-2.87K,1%,1/16W,CHA CS22872FB10              2       
Q_RES_0402LF-200K,1%,1/16W,CHIA CS42002FB12              1       
Q_RES_0402LF-20K,1%,1/16W,CHIPA CS32002FB29              2       
Q_RES_0402LF-22,1%,1/16W,CHIP,A CS02202FB02              2       
Q_RES_0402LF-22,5%,1/16W,CHIP,A CS02202JB22              6       
Q_RES_0402LF-220,5%,1/16W,CHIPA CS12202JB24              3       
Q_RES_0402LF-240,1%,1/16W,CHIPA CS12402FB03              2       
Q_RES_0402LF-25.5K,1%,1/16W,CHA CS32552FB11              1       
Q_RES_0402LF-2K,1%,1/16W,CHIP,A CS22002FB19              15      
Q_RES_0402LF-2K,1%,1/16W,EMPTYA CS22002FB19              1       
Q_RES_0402LF-33       ,1%  ,1/A CS03302FB19              226     
Q_RES_0402LF-33       ,1%  ,1/B CS03302FB19              29      
Q_RES_0402LF-330,1%,1/16W,CHIPA CS13302FB11              1       
Q_RES_0402LF-4.7K,1%,1/16W,CHIA CS24702FB10              23      
Q_RES_0402LF-4.7K,1%,1/16W,EMPA CS24702FB10              13      
Q_RES_0402LF-4.7K,5%,1/16W,CHIA CS24702JB38              114     
Q_RES_0402LF-4.7K,5%,1/16W,EMPA CS24702JB38              15      
Q_RES_0402LF-470K,1%,1/16W,CHIA CS44702FB13              1       
Q_RES_0402LF-47K,1%,1/16W,CHIPA CS34702FB11              1       
Q_RES_0402LF-47K,5%,1/16W,EMPTA CS34702JB21              1       
Q_RES_0402LF-49.9     ,1%  ,1/A CS04992FB31              2       
Q_RES_0402LF-499,1%,1/16W,CHIPA CS14992FB24              1       
Q_RES_0402LF-5.1,5%,1/16W,CHIPA CS-5102JB03              2       
Q_RES_0402LF-5.36K,1%,1/16W,CHA CS25362FB15              1       
Q_RES_0402LF-51.1K,1%,1/16W,CHA CS35112FB17              1       
Q_RES_0402LF-56K,1%,1/16W,CHIPA CS35602FB11              1       
Q_RES_0402LF-60.4,1%,1/16W,CHIA CS06042FB14              2       
Q_RES_0402LF-60.4K,1%,1/16W,CHA CS36042FB10              1       
Q_RES_0402LF-665,1%,1/16W,CHIPA CS16652FB04              1       
Q_RES_0402LF-681K,1%,1/16W,CHIA CS46812FB00              1       
Q_RES_0402LF-750,1%,1/16W,CHIPA CS17502FB19              8       
Q_RES_0402LF-8.2K     ,5%  ,1/A CS28202JB14              3       
Q_RES_0402LF-8.66K,1%,1/16W,CHA CS28662FB14              1       
Q_RES_0402LF-91K,1%,1/16W,CHIPA CS39102FB05              1       
Q_RES_0603-0,5%,1/10W,EMPTY,TMA CS00003J951              1       
Q_XTAL_4P_13BI_24GND-25MHZ,SMLA BG625000802              1       
RT9059GQW-RT9059GQW,SMLF,IC,ALA AL009059000              2       
SCHOTTKY_AC-RB161SS-20T2R,SMLFA BC0161SS000              1       
SCHOTTKY_AC-SS0530,SMLF,EMPTY,A BCSS0530Z00              1       
SCHOTTKY_AC-SS0530,SMLF,IC,BCSA BCSS0530Z00              1       
SCONN11_9192031111LF-SCONN11_9A DFHS11FS009              2       
SCONN13_502240130C001-SCONN13_A DFHD13MR071              1       
SCONN14_RS6QU0001-SCONN14_RS6-A DFTJ14FR046              1       
SCONN16_ACASPI006P06-SCONN16_AA DG016000006              2       
SCONN20_3VM11207D7307H-SCONN20A DFHS20FR233              1       
SCONN5_2UB2141000111F-SCONN5_2A DFHS05FR105              1       
SN74LVC1G07DBVR_SMLF-SN74LVC1GA AL1G0007024              1       
SN74LVC1G07DCKR-SN74LVC1G07DCKA AL1G0007016              1       
SN74LVC1G3157DCKR-SN74LVC1G315A AL1G3157001              2       
SN74LVC2G07DCKR_SMLF-SN74LVC2GA AL002G07006              2       
SW2S_TA31E2KQTR-SW2S_TA3-1E2K-A DHP01E2KQ00              2       
SW4S_DHNF02FTVTR-SW4S_DHNF-02FA DHP00002F00              3       
TMP75AIDGKR-TMP75AIDGKR,SMLF,IA AL0000750E3              1       
TPD2EUSB30DRTR_SMLF-TPD2EUSB30A AL2EUSB3000              1       
TPD4E001DBVR-TPD4E001DBVR,SMLFA BC01DBVR000              3       
TPD4E001DBVR-TPD4E001DBVR,SMLFB BC01DBVR000              2       
TPS22965DSGR-TPS22965DSGR,SMLFA AL022965000              1       
TPS2553DBVR1-TPS2553DBVR-1,SMLA AL002553002              1       
TPS3808G33DBVR-TPS3808G33DBVR,A AL380833000              1       

Total                                     1328    
END CONCISE PART LIST
